# TIMECARD (Time Appliance Project (Time Card)) — schematic netlist excerpt (pin names and nets, part order shuffled) for the footprints in the layout excerpt that follows; sources: Cadence DE-HDL packaged netlist, KiCad conversion of R4006-B0001-02_R01.brd

C282  CAPACITOR  10UF 25V 20%  pkg SMC_0805R_H057  page 21 : \1\ = XP5R0V_MAC ; \2\ = SG
L4  FERRITEBEAD  600OHM 25%  pkg SMC_0603R_H037  page 24 : \1\ = XP3R3V_FT4232 ; \2\ = XP3R3V_VPLL

(kicad_pcb
	(version 20260206)
	(generator "pcbnew")
	(generator_version "10.0")
	(general
		(thickness 1.6)
		(legacy_teardrops no)
	)
	(paper "A4")
	(title_block
		(title "timecard-production-celestica-r4006 — R4006-B0001-02_R01.brd")
		(comment 1 "Time Appliance Project (Time Card) / footprints 1069-1070 of 1113")
	)
	(layers
		(0 "F.Cu" signal "TOP")
		(4 "In1.Cu" signal "L02_GND1")
		(6 "In2.Cu" signal "L03_SIG1")
		(8 "In3.Cu" signal "L04_GND2")
		(10 "In4.Cu" signal "L05_VCC1")
		(12 "In5.Cu" signal "L06_VCC2")
		(14 "In6.Cu" signal "L07_GND3")
		(16 "In7.Cu" signal "L08_SIG2")
		(18 "In8.Cu" signal "L09_GND4")
		(2 "B.Cu" signal "BOTTOM")
		(9 "F.Adhes" user "F.Adhesive")
		(11 "B.Adhes" user "B.Adhesive")
		(13 "F.Paste" user "Package Geometry/Pastemask Top")
		(15 "B.Paste" user "Package Geometry/Pastemask Bottom")
		(5 "F.SilkS" user "Ref Des/Silkscreen Top")
		(7 "B.SilkS" user "Ref Des/Silkscreen Bottom")
		(1 "F.Mask" user "Board Geometry/Soldermask Top")
		(3 "B.Mask" user "Board Geometry/Soldermask Bottom")
		(17 "Dwgs.User" user "User.Drawings")
		(19 "Cmts.User" user "User.Comments")
		(21 "Eco1.User" user "User.Eco1")
		(23 "Eco2.User" user "User.Eco2")
		(25 "Edge.Cuts" user "Board Geometry/Outline")
		(27 "Margin" user)
		(31 "F.CrtYd" user "Package Geometry/Place Bound Top")
		(29 "B.CrtYd" user "Package Geometry/Place Bound Bottom")
		(35 "F.Fab" user "Ref Des/Assembly Top")
		(33 "B.Fab" user "Ref Des/Assembly Bottom")
	)
	(footprint ""
		(layer "B.Cu")
		(at 27.686 -88.519 -90)
		(property "Reference" "L4"
			(at 2.286 0.03937 270)
			(unlocked yes)
			(layer "B.SilkS")
			(effects
				(font
					(size 0.7874 0.5842)
					(thickness 0.1524)
				)
				(justify mirror)
			)
		)
		(property "Value" "VAL*"
			(at -0.014732 2.526538 270)
			(unlocked yes)
			(layer "B.Fab")
			(hide yes)
			(effects
				(font
					(size 0.7874 0.5842)
					(thickness 0.000001)
				)
				(justify mirror)
			)
		)
		(property "Tolerance" "TOL*"
			(at -0.014732 3.503676 270)
			(unlocked yes)
			(layer "Cmts.User")
			(hide yes)
			(effects
				(font
					(size 0.7874 0.5842)
					(thickness 0.000001)
				)
				(justify mirror)
			)
		)
		(property "User Part Number" "PARTNUM*"
			(at -0.02794 4.480814 270)
			(unlocked yes)
			(layer "Cmts.User")
			(hide yes)
			(effects
				(font
					(size 0.7874 0.5842)
					(thickness 0.000001)
				)
				(justify mirror)
			)
		)
		(property "Device Type" "FERRITEBEAD-G191-10097-01,600OA"
			(at -0.014732 1.600708 270)
			(unlocked yes)
			(layer "B.Fab")
			(hide yes)
			(effects
				(font
					(size 0.7874 0.5842)
					(thickness 0.000001)
				)
				(justify mirror)
			)
		)
		(duplicate_pad_numbers_are_jumpers no)
		(fp_line
			(start -1.3208 0.7112)
			(end 1.3208 0.7112)
			(stroke
				(width 0.1)
				(type default)
			)
			(layer "B.SilkS")
		)
		(fp_line
			(start 1.3208 0.7112)
			(end 1.3208 -0.7112)
			(stroke
				(width 0.1)
				(type default)
			)
			(layer "B.SilkS")
		)
		(fp_line
			(start -1.3208 -0.7112)
			(end -1.3208 0.7112)
			(stroke
				(width 0.1)
				(type default)
			)
			(layer "B.SilkS")
		)
		(fp_line
			(start 1.3208 -0.7112)
			(end -1.3208 -0.7112)
			(stroke
				(width 0.1)
				(type default)
			)
			(layer "B.SilkS")
		)
		(fp_rect
			(start 1.3208 0.7112)
			(end -1.3208 -0.7112)
			(stroke
				(width 0)
				(type default)
			)
			(fill no)
			(layer "B.CrtYd")
		)
		(fp_line
			(start -0.8128 0.4572)
			(end 0.8128 0.4572)
			(stroke
				(width 0.1)
				(type default)
			)
			(layer "B.Fab")
		)
		(fp_line
			(start 0.8128 0.4572)
			(end 0.8128 -0.4572)
			(stroke
				(width 0.1)
				(type default)
			)
			(layer "B.Fab")
		)
		(fp_line
			(start -0.8128 -0.4572)
			(end -0.8128 0.4572)
			(stroke
				(width 0.1)
				(type default)
			)
			(layer "B.Fab")
		)
		(fp_line
			(start 0.8128 -0.4572)
			(end -0.8128 -0.4572)
			(stroke
				(width 0.1)
				(type default)
			)
			(layer "B.Fab")
		)
		(pad "1" smd rect
			(at 0.6858 0 90)
			(size 0.762 0.8636)
			(layers "B.Cu" "B.Mask" "B.Paste")
			(net "XP3R3V_FT4232")
		)
		(pad "2" smd rect
			(at -0.6858 0 90)
			(size 0.762 0.8636)
			(layers "B.Cu" "B.Mask" "B.Paste")
			(net "XP3R3V_VPLL")
		)
		(zone
			(layer "B.Cu")
			(hatch none 0.5)
			(connect_pads
				(clearance 0)
			)
			(min_thickness 0.25)
			(keepout
				(tracks not_allowed)
				(vias allowed)
				(pads allowed)
				(copperpour not_allowed)
				(footprints allowed)
			)
			(placement
				(enabled no)
				(sheetname "")
			)
			(fill
				(thermal_gap 0.5)
				(thermal_bridge_width 0.5)
				(island_removal_mode 0)
			)
			(polygon
				(pts
					(xy 27.2288 -88.3666) (xy 28.1432 -88.3666) (xy 28.1432 -88.6714) (xy 27.2288 -88.6714)
				)
			)
		)
		(zone
			(layer "B.Cu")
			(hatch none 0.5)
			(connect_pads
				(clearance 0)
			)
			(min_thickness 0.25)
			(keepout
				(tracks allowed)
				(vias not_allowed)
				(pads allowed)
				(copperpour not_allowed)
				(footprints allowed)
			)
			(placement
				(enabled no)
				(sheetname "")
			)
			(fill
				(thermal_gap 0.5)
				(thermal_bridge_width 0.5)
				(island_removal_mode 0)
			)
			(polygon
				(pts
					(xy 27.2288 -88.3666) (xy 28.1432 -88.3666) (xy 28.1432 -88.6714) (xy 27.2288 -88.6714)
				)
			)
		)
	)
	(footprint ""
		(layer "B.Cu")
		(at 77.089 -73.152 -90)
		(property "Reference" "C282"
			(at -3.556 0.03937 270)
			(unlocked yes)
			(layer "B.SilkS")
			(effects
				(font
					(size 0.7874 0.5842)
					(thickness 0.1524)
				)
				(justify mirror)
			)
		)
		(property "Value" "VAL*"
			(at -0.0762 3.134106 270)
			(unlocked yes)
			(layer "B.Fab")
			(hide yes)
			(effects
				(font
					(size 0.7874 0.5842)
					(thickness 0.1524)
				)
				(justify mirror)
			)
		)
		(property "Device Type" "CAPACITOR-G107-0F106-EM,10UF,2A"
			(at -0.0508 2.194306 270)
			(unlocked yes)
			(layer "B.Fab")
			(hide yes)
			(effects
				(font
					(size 0.7874 0.5842)
					(thickness 0.1524)
				)
				(justify mirror)
			)
		)
		(property "User Part Number" "PARTNUM*"
			(at -0.1016 5.013706 270)
			(unlocked yes)
			(layer "Cmts.User")
			(hide yes)
			(effects
				(font
					(size 0.7874 0.5842)
					(thickness 0.1524)
				)
				(justify mirror)
			)
		)
		(property "Tolerance" "TOL*"
			(at -0.0762 4.048506 270)
			(unlocked yes)
			(layer "Cmts.User")
			(hide yes)
			(effects
				(font
					(size 0.7874 0.5842)
					(thickness 0.1524)
				)
				(justify mirror)
			)
		)
		(duplicate_pad_numbers_are_jumpers no)
		(fp_line
			(start -1.5748 0.9398)
			(end -1.5748 -0.9398)
			(stroke
				(width 0.1)
				(type default)
			)
			(layer "B.SilkS")
		)
		(fp_line
			(start 1.5748 0.9398)
			(end -1.5748 0.9398)
			(stroke
				(width 0.1)
				(type default)
			)
			(layer "B.SilkS")
		)
		(fp_line
			(start -1.5748 -0.9398)
			(end 1.5748 -0.9398)
			(stroke
				(width 0.1)
				(type default)
			)
			(layer "B.SilkS")
		)
		(fp_line
			(start 1.5748 -0.9398)
			(end 1.5748 0.9398)
			(stroke
				(width 0.1)
				(type default)
			)
			(layer "B.SilkS")
		)
		(fp_rect
			(start 1.5748 -0.9398)
			(end -1.5748 0.9398)
			(stroke
				(width 0)
				(type default)
			)
			(fill no)
			(layer "B.CrtYd")
		)
		(fp_line
			(start -1.016 0.635)
			(end -1.016 -0.635)
			(stroke
				(width 0.1)
				(type default)
			)
			(layer "B.Fab")
		)
		(fp_line
			(start 1.016 0.635)
			(end -1.016 0.635)
			(stroke
				(width 0.1)
				(type default)
			)
			(layer "B.Fab")
		)
		(fp_line
			(start -1.016 -0.635)
			(end 1.016 -0.635)
			(stroke
				(width 0.1)
				(type default)
			)
			(layer "B.Fab")
		)
		(fp_line
			(start 1.016 -0.635)
			(end 1.016 0.635)
			(stroke
				(width 0.1)
				(type default)
			)
			(layer "B.Fab")
		)
		(pad "1" smd rect
			(at 0.8382 0 90)
			(size 0.9652 1.3716)
			(layers "B.Cu" "B.Mask" "B.Paste")
			(net "XP5R0V_MAC")
		)
		(pad "2" smd rect
			(at -0.8382 0 90)
			(size 0.9652 1.3716)
			(layers "B.Cu" "B.Mask" "B.Paste")
			(net "SG")
		)
		(zone
			(layer "B.Cu")
			(hatch none 0.5)
			(connect_pads
				(clearance 0)
			)
			(min_thickness 0.25)
			(keepout
				(tracks allowed)
				(vias not_allowed)
				(pads allowed)
				(copperpour not_allowed)
				(footprints allowed)
			)
			(placement
				(enabled no)
				(sheetname "")
			)
			(fill
				(thermal_gap 0.5)
				(thermal_bridge_width 0.5)
				(island_removal_mode 0)
			)
			(polygon
				(pts
					(xy 77.724 -72.9234) (xy 77.724 -73.3806) (xy 76.454 -73.3806) (xy 76.454 -72.9234)
				)
			)
		)
	)
)
